(kicad_pcb
	(version 20241229)
	(generator "pcbnew")
	(generator_version "9.0")
	(general
		(thickness 1.552)
		(legacy_teardrops no)
	)
	(paper "A4")
	(title_block
		(date "2023-07-25")
		(rev "1.1.4")
		(comment 9 "footprints 115-119 of 379")
	)
	(layers
		(0 "F.Cu" signal)
		(4 "In1.Cu" signal)
		(6 "In2.Cu" signal)
		(8 "In3.Cu" signal)
		(10 "In4.Cu" signal)
		(12 "In5.Cu" signal)
		(14 "In6.Cu" signal)
		(2 "B.Cu" signal)
		(9 "F.Adhes" user "F.Adhesive")
		(11 "B.Adhes" user "B.Adhesive")
		(13 "F.Paste" user)
		(15 "B.Paste" user)
		(5 "F.SilkS" user "F.Silkscreen")
		(7 "B.SilkS" user "B.Silkscreen")
		(1 "F.Mask" user)
		(3 "B.Mask" user)
		(17 "Dwgs.User" user "User.Drawings")
		(19 "Cmts.User" user "User.Comments")
		(21 "Eco1.User" user "User.Eco1")
		(23 "Eco2.User" user "User.Eco2")
		(25 "Edge.Cuts" user)
		(27 "Margin" user)
		(31 "F.CrtYd" user "F.Courtyard")
		(29 "B.CrtYd" user "B.Courtyard")
		(35 "F.Fab" user)
		(33 "B.Fab" user)
	)
	(footprint "antmicro-footprints:C_0402_1005Metric"
		(layer "F.Cu")
		(at 88.5 75.4 180)
		(descr "Capacitor SMD 0402")
		(tags "capacitor SMD 0402")
		(property "Reference" "C53"
			(at 0.42 6.26 0)
			(layer "F.SilkS")
			(effects
				(font
					(size 0.65 0.65)
					(thickness 0.15)
				)
				(justify right bottom)
			)
		)
		(property "Value" "C_1u_0402"
			(at 0 1.4 0)
			(layer "F.Fab")
			(hide yes)
			(effects
				(font
					(size 0.7 0.7)
					(thickness 0.15)
				)
				(justify right bottom)
			)
		)
		(property "Datasheet" "https://product.tdk.com/en/search/capacitor/ceramic/mlcc/info?part_no=C1005X6S1A105K050BC"
			(at 0 0 180)
			(layer "F.Fab")
			(hide yes)
			(effects
				(font
					(size 1.27 1.27)
					(thickness 0.15)
				)
			)
		)
		(property "Description" "SMD Multilayer Ceramic Capacitor, 1 µF, 10 V, 0402 [1005 Metric], ± 10%, X6S, C"
			(at 0 0 180)
			(layer "F.Fab")
			(hide yes)
			(effects
				(font
					(size 1.27 1.27)
					(thickness 0.15)
				)
			)
		)
		(property "Author" "Antmicro"
			(at 177 150.8 0)
			(layer "F.Fab")
			(hide yes)
			(effects
				(font
					(size 1 1)
					(thickness 0.15)
				)
			)
		)
		(property "Dielectric" ""
			(at 177 150.8 0)
			(layer "F.Fab")
			(hide yes)
			(effects
				(font
					(size 1 1)
					(thickness 0.15)
				)
			)
		)
		(property "License" "Apache-2.0"
			(at 177 150.8 0)
			(layer "F.Fab")
			(hide yes)
			(effects
				(font
					(size 1 1)
					(thickness 0.15)
				)
			)
		)
		(property "MPN" "C1005X6S1A105K050BC"
			(at 177 150.8 0)
			(layer "F.Fab")
			(hide yes)
			(effects
				(font
					(size 1 1)
					(thickness 0.15)
				)
			)
		)
		(property "Manufacturer" "TDK"
			(at 177 150.8 0)
			(layer "F.Fab")
			(hide yes)
			(effects
				(font
					(size 1 1)
					(thickness 0.15)
				)
			)
		)
		(property "Val" "1u"
			(at 177 150.8 0)
			(layer "F.Fab")
			(hide yes)
			(effects
				(font
					(size 1 1)
					(thickness 0.15)
				)
			)
		)
		(property "Voltage" ""
			(at 177 150.8 0)
			(layer "F.Fab")
			(hide yes)
			(effects
				(font
					(size 1 1)
					(thickness 0.15)
				)
			)
		)
		(sheetname "/SDI/")
		(sheetfile "sdi.kicad_sch")
		(attr smd)
		(fp_rect
			(start -0.925 -0.47)
			(end 0.925 0.47)
			(stroke
				(width 0.05)
				(type default)
			)
			(fill no)
			(layer "F.CrtYd")
		)
		(fp_line
			(start 0.504 0.248)
			(end -0.494 0.248)
			(stroke
				(width 0.15)
				(type solid)
			)
			(layer "F.Fab")
		)
		(fp_line
			(start 0.504 -0.25)
			(end 0.504 0.248)
			(stroke
				(width 0.15)
				(type solid)
			)
			(layer "F.Fab")
		)
		(fp_line
			(start -0.494 0.248)
			(end -0.494 -0.25)
			(stroke
				(width 0.15)
				(type solid)
			)
			(layer "F.Fab")
		)
		(fp_line
			(start -0.494 -0.25)
			(end 0.504 -0.25)
			(stroke
				(width 0.15)
				(type solid)
			)
			(layer "F.Fab")
		)
		(fp_text user "Author: Antmicro"
			(at -0.939 3.399 180)
			(layer "F.Fab")
			(effects
				(font
					(size 0.7 0.7)
					(thickness 0.15)
				)
				(justify left bottom)
			)
		)
		(fp_text user "License: Apache-2.0"
			(at -0.939 5.799 180)
			(layer "F.Fab")
			(effects
				(font
					(size 0.7 0.7)
					(thickness 0.15)
				)
				(justify left bottom)
			)
		)
		(fp_text user "${REFERENCE}"
			(at -0.939 4.599 180)
			(layer "F.Fab")
			(effects
				(font
					(size 0.7 0.7)
					(thickness 0.15)
				)
				(justify left bottom)
			)
		)
		(pad "1" smd roundrect
			(at -0.48 0 180)
			(size 0.59 0.64)
			(layers "F.Cu" "F.Mask" "F.Paste")
			(roundrect_rratio 0.25)
			(net 7 "/SDI/SDI_P")
			(pintype "passive")
		)
		(pad "2" smd roundrect
			(at 0.48 0 180)
			(size 0.59 0.64)
			(layers "F.Cu" "F.Mask" "F.Paste")
			(roundrect_rratio 0.25)
			(net 243 "/SDI/SDI_IN_F")
			(pintype "passive")
		)
	)
	(footprint "antmicro-footprints:TP_SMD_0.75mm"
		(layer "F.Cu")
		(at 126.89 106.45)
		(property "Reference" "TP22"
			(at 0 -0.6 0)
			(layer "F.SilkS")
			(effects
				(font
					(size 0.65 0.65)
					(thickness 0.15)
				)
				(justify left bottom)
			)
		)
		(property "Value" "TP_0.75mm_SMD"
			(at 0 1.2 0)
			(layer "F.Fab")
			(hide yes)
			(effects
				(font
					(size 0.7 0.7)
					(thickness 0.15)
				)
				(justify left bottom)
			)
		)
		(property "Description" "SMT test point"
			(at 0 0 0)
			(layer "F.Fab")
			(hide yes)
			(effects
				(font
					(size 1.27 1.27)
					(thickness 0.15)
				)
			)
		)
		(property "Author" "Antmicro"
			(at 0 0 0)
			(layer "F.Fab")
			(hide yes)
			(effects
				(font
					(size 1 1)
					(thickness 0.15)
				)
			)
		)
		(property "License" "Apache-2.0"
			(at 0 0 0)
			(layer "F.Fab")
			(hide yes)
			(effects
				(font
					(size 1 1)
					(thickness 0.15)
				)
			)
		)
		(property "MPN" ""
			(at 0 0 0)
			(layer "F.Fab")
			(hide yes)
			(effects
				(font
					(size 1 1)
					(thickness 0.15)
				)
			)
		)
		(property "Manufacturer" ""
			(at 0 0 0)
			(layer "F.Fab")
			(hide yes)
			(effects
				(font
					(size 1 1)
					(thickness 0.15)
				)
			)
		)
		(sheetname "/FPGA/")
		(sheetfile "fpga.kicad_sch")
		(attr exclude_from_pos_files)
		(fp_circle
			(center 0 0)
			(end 0.475 0)
			(stroke
				(width 0.05)
				(type default)
			)
			(fill no)
			(layer "F.CrtYd")
		)
		(fp_text user "Author: Antmicro"
			(at -0.4 3.901 0)
			(layer "F.Fab")
			(effects
				(font
					(size 0.7 0.7)
					(thickness 0.15)
				)
				(justify left bottom)
			)
		)
		(fp_text user "License: Apache-2.0"
			(at -0.4 5.101 0)
			(layer "F.Fab")
			(effects
				(font
					(size 0.7 0.7)
					(thickness 0.15)
				)
				(justify left bottom)
			)
		)
		(fp_text user "${REFERENCE}"
			(at -0.4 2.7 0)
			(layer "F.Fab")
			(effects
				(font
					(size 0.7 0.7)
					(thickness 0.15)
				)
				(justify left bottom)
			)
		)
		(pad "1" smd circle
			(at 0 0)
			(size 0.75 0.75)
			(layers "F.Cu" "F.Mask")
			(net 15 "/FPGA/INITN")
			(pinfunction "1")
			(pintype "passive")
		)
	)
	(footprint "antmicro-footprints:C_0603_1608Metric"
		(layer "F.Cu")
		(at 138.79 115.9 90)
		(descr "Capacitor SMD 0603")
		(tags "capacitor 0603")
		(property "Reference" "C30"
			(at -3.44 0.44 90)
			(layer "F.SilkS")
			(effects
				(font
					(size 0.65 0.65)
					(thickness 0.15)
				)
				(justify left bottom)
			)
		)
		(property "Value" "C_1u_0603"
			(at 0 1.6 90)
			(layer "F.Fab")
			(hide yes)
			(effects
				(font
					(size 0.7 0.7)
					(thickness 0.15)
				)
				(justify left bottom)
			)
		)
		(property "Datasheet" "https://spicat.kyocera-avx.com/product/mlcc/chartview/0603YD105KAT2A/"
			(at 0 0 90)
			(layer "F.Fab")
			(hide yes)
			(effects
				(font
					(size 1.27 1.27)
					(thickness 0.15)
				)
			)
		)
		(property "Description" "SMD Multilayer Ceramic Capacitor, 1 µF, 16 V, 0603 [1608 Metric], ± 10%, X5R, AVX 0603 MLCC"
			(at 0 0 90)
			(layer "F.Fab")
			(hide yes)
			(effects
				(font
					(size 1.27 1.27)
					(thickness 0.15)
				)
			)
		)
		(property "Author" "Antmicro"
			(at 254.69 -22.89 0)
			(layer "F.Fab")
			(hide yes)
			(effects
				(font
					(size 1 1)
					(thickness 0.15)
				)
			)
		)
		(property "Dielectric" ""
			(at 254.69 -22.89 0)
			(layer "F.Fab")
			(hide yes)
			(effects
				(font
					(size 1 1)
					(thickness 0.15)
				)
			)
		)
		(property "License" "Apache-2.0"
			(at 254.69 -22.89 0)
			(layer "F.Fab")
			(hide yes)
			(effects
				(font
					(size 1 1)
					(thickness 0.15)
				)
			)
		)
		(property "MPN" "0603YD105KAT2A"
			(at 254.69 -22.89 0)
			(layer "F.Fab")
			(hide yes)
			(effects
				(font
					(size 1 1)
					(thickness 0.15)
				)
			)
		)
		(property "Manufacturer" "KYOCERA AVX"
			(at 254.69 -22.89 0)
			(layer "F.Fab")
			(hide yes)
			(effects
				(font
					(size 1 1)
					(thickness 0.15)
				)
			)
		)
		(property "Val" "1u"
			(at 254.69 -22.89 0)
			(layer "F.Fab")
			(hide yes)
			(effects
				(font
					(size 1 1)
					(thickness 0.15)
				)
			)
		)
		(property "Voltage" ""
			(at 254.69 -22.89 0)
			(layer "F.Fab")
			(hide yes)
			(effects
				(font
					(size 1 1)
					(thickness 0.15)
				)
			)
		)
		(sheetname "/Power Supply/")
		(sheetfile "supply.kicad_sch")
		(attr smd)
		(fp_line
			(start -0.15 -0.4)
			(end 0.15 -0.4)
			(stroke
				(width 0.15)
				(type solid)
			)
			(layer "F.SilkS")
		)
		(fp_line
			(start -0.15 0.4)
			(end 0.15 0.4)
			(stroke
				(width 0.15)
				(type solid)
			)
			(layer "F.SilkS")
		)
		(fp_rect
			(start -1.25 -0.65)
			(end 1.25 0.65)
			(stroke
				(width 0.05)
				(type solid)
			)
			(fill no)
			(layer "F.CrtYd")
		)
		(fp_rect
			(start -0.8 -0.4)
			(end 0.8 0.4)
			(stroke
				(width 0.15)
				(type solid)
			)
			(fill no)
			(layer "F.Fab")
		)
		(fp_text user "License: Apache-2.0"
			(at -1.682 5.895 90)
			(layer "F.Fab")
			(effects
				(font
					(size 0.7 0.7)
					(thickness 0.15)
				)
				(justify left bottom)
			)
		)
		(fp_text user "Author: Antmicro"
			(at -1.682 4.894 90)
			(layer "F.Fab")
			(effects
				(font
					(size 0.7 0.7)
					(thickness 0.15)
				)
				(justify left bottom)
			)
		)
		(fp_text user "${REFERENCE}"
			(at -1.682 3.895 90)
			(layer "F.Fab")
			(effects
				(font
					(size 0.7 0.7)
					(thickness 0.15)
				)
				(justify left bottom)
			)
		)
		(pad "1" smd roundrect
			(at -0.7 0 90)
			(size 0.8 1)
			(layers "F.Cu" "F.Mask" "F.Paste")
			(roundrect_rratio 0.2)
			(net 1 "GND")
			(pintype "passive")
		)
		(pad "2" smd roundrect
			(at 0.7 0 90)
			(size 0.8 1)
			(layers "F.Cu" "F.Mask" "F.Paste")
			(roundrect_rratio 0.2)
			(net 3 "+1V2")
			(pintype "passive")
		)
	)
	(footprint "antmicro-footprints:R_0402_1005Metric"
		(layer "F.Cu")
		(at 163.19 59.04 180)
		(descr "Resistor SMD 0402")
		(tags "resistor SMD 0402")
		(property "Reference" "R26"
			(at 1.06 0.7 180)
			(layer "F.SilkS")
			(effects
				(font
					(size 0.65 0.65)
					(thickness 0.15)
				)
				(justify left bottom)
			)
		)
		(property "Value" "R_33k_0402"
			(at 0 1.4 180)
			(layer "F.Fab")
			(hide yes)
			(effects
				(font
					(size 0.7 0.7)
					(thickness 0.15)
				)
				(justify left bottom)
			)
		)
		(property "Datasheet" "https://www.bourns.com/docs/product-datasheets/cr.pdf"
			(at 0 0 180)
			(layer "F.Fab")
			(hide yes)
			(effects
				(font
					(size 1.27 1.27)
					(thickness 0.15)
				)
			)
		)
		(property "Description" "SMD Chip Resistor, 33 kohm, ± 1%, 62.5 mW, 0402 [1005 Metric], Thick Film, General Purpose"
			(at 0 0 180)
			(layer "F.Fab")
			(hide yes)
			(effects
				(font
					(size 1.27 1.27)
					(thickness 0.15)
				)
			)
		)
		(property "Author" "Antmicro"
			(at 326.38 118.08 0)
			(layer "F.Fab")
			(hide yes)
			(effects
				(font
					(size 1 1)
					(thickness 0.15)
				)
			)
		)
		(property "License" "Apache-2.0"
			(at 326.38 118.08 0)
			(layer "F.Fab")
			(hide yes)
			(effects
				(font
					(size 1 1)
					(thickness 0.15)
				)
			)
		)
		(property "MPN" "CR0402-FX-3302GLF"
			(at 326.38 118.08 0)
			(layer "F.Fab")
			(hide yes)
			(effects
				(font
					(size 1 1)
					(thickness 0.15)
				)
			)
		)
		(property "Manufacturer" "Bourns"
			(at 326.38 118.08 0)
			(layer "F.Fab")
			(hide yes)
			(effects
				(font
					(size 1 1)
					(thickness 0.15)
				)
			)
		)
		(property "Tolerance" "1%"
			(at 326.38 118.08 0)
			(layer "F.Fab")
			(hide yes)
			(effects
				(font
					(size 1 1)
					(thickness 0.15)
				)
			)
		)
		(property "Val" "33k"
			(at 326.38 118.08 0)
			(layer "F.Fab")
			(hide yes)
			(effects
				(font
					(size 1 1)
					(thickness 0.15)
				)
			)
		)
		(sheetname "/Power Supply/")
		(sheetfile "supply.kicad_sch")
		(attr smd)
		(fp_rect
			(start -0.925 -0.47)
			(end 0.925 0.47)
			(stroke
				(width 0.05)
				(type default)
			)
			(fill no)
			(layer "F.CrtYd")
		)
		(fp_rect
			(start -0.5 -0.25)
			(end 0.5 0.25)
			(stroke
				(width 0.15)
				(type solid)
			)
			(fill no)
			(layer "F.Fab")
		)
		(fp_text user "${REFERENCE}"
			(at -0.95 3.168 180)
			(layer "F.Fab")
			(effects
				(font
					(size 0.7 0.7)
					(thickness 0.15)
				)
				(justify left bottom)
			)
		)
		(fp_text user "License: Apache-2.0"
			(at -0.95 5.169 180)
			(layer "F.Fab")
			(effects
				(font
					(size 0.7 0.7)
					(thickness 0.15)
				)
				(justify left bottom)
			)
		)
		(fp_text user "Author: Antmicro"
			(at -0.95 4.169 180)
			(layer "F.Fab")
			(effects
				(font
					(size 0.7 0.7)
					(thickness 0.15)
				)
				(justify left bottom)
			)
		)
		(pad "1" smd roundrect
			(at -0.48 0 180)
			(size 0.59 0.64)
			(layers "F.Cu" "F.Mask" "F.Paste")
			(roundrect_rratio 0.25)
			(net 270 "Net-(U7-FB)")
			(pintype "passive")
		)
		(pad "2" smd roundrect
			(at 0.48 0 180)
			(size 0.59 0.64)
			(layers "F.Cu" "F.Mask" "F.Paste")
			(roundrect_rratio 0.25)
			(net 275 "/Power Supply/3V3_OUT")
			(pintype "passive")
		)
	)
	(footprint "antmicro-footprints:R_0402_1005Metric"
		(layer "F.Cu")
		(at 167.2 91.6)
		(descr "Resistor SMD 0402")
		(tags "resistor SMD 0402")
		(property "Reference" "R124"
			(at -3.67 0.34 0)
			(layer "F.SilkS")
			(effects
				(font
					(size 0.65 0.65)
					(thickness 0.15)
				)
				(justify left bottom)
			)
		)
		(property "Value" "R_0R_0402"
			(at 0 1.4 0)
			(layer "F.Fab")
			(hide yes)
			(effects
				(font
					(size 0.7 0.7)
					(thickness 0.15)
				)
				(justify left bottom)
			)
		)
		(property "Datasheet" "https://industrial.panasonic.com/cdbs/www-data/pdf/RDA0000/AOA0000C301.pdf"
			(at 0 0 0)
			(layer "F.Fab")
			(hide yes)
			(effects
				(font
					(size 1.27 1.27)
					(thickness 0.15)
				)
			)
		)
		(property "Description" "SMD Chip Resistor, Jumper, 0 ohm, 100 mW, 0402 [1005 Metric], Thick Film, General Purpose"
			(at 0 0 0)
			(layer "F.Fab")
			(hide yes)
			(effects
				(font
					(size 1.27 1.27)
					(thickness 0.15)
				)
			)
		)
		(property "Author" "Antmicro"
			(at 0 0 0)
			(layer "F.Fab")
			(hide yes)
			(effects
				(font
					(size 1 1)
					(thickness 0.15)
				)
			)
		)
		(property "Current" "1A"
			(at 0 0 0)
			(layer "F.Fab")
			(hide yes)
			(effects
				(font
					(size 1 1)
					(thickness 0.15)
				)
			)
		)
		(property "License" "Apache-2.0"
			(at 0 0 0)
			(layer "F.Fab")
			(hide yes)
			(effects
				(font
					(size 1 1)
					(thickness 0.15)
				)
			)
		)
		(property "MPN" "ERJ2GE0R00X"
			(at 0 0 0)
			(layer "F.Fab")
			(hide yes)
			(effects
				(font
					(size 1 1)
					(thickness 0.15)
				)
			)
		)
		(property "Manufacturer" "Panasonic"
			(at 0 0 0)
			(layer "F.Fab")
			(hide yes)
			(effects
				(font
					(size 1 1)
					(thickness 0.15)
				)
			)
		)
		(property "Tolerance" "~"
			(at 0 0 0)
			(layer "F.Fab")
			(hide yes)
			(effects
				(font
					(size 1 1)
					(thickness 0.15)
				)
			)
		)
		(property "Val" "0R"
			(at 0 0 0)
			(layer "F.Fab")
			(hide yes)
			(effects
				(font
					(size 1 1)
					(thickness 0.15)
				)
			)
		)
		(sheetname "/Peripherals/")
		(sheetfile "peripherals.kicad_sch")
		(attr smd)
		(fp_rect
			(start -0.925 -0.47)
			(end 0.925 0.47)
			(stroke
				(width 0.05)
				(type default)
			)
			(fill no)
			(layer "F.CrtYd")
		)
		(fp_rect
			(start -0.5 -0.25)
			(end 0.5 0.25)
			(stroke
				(width 0.15)
				(type solid)
			)
			(fill no)
			(layer "F.Fab")
		)
		(fp_text user "License: Apache-2.0"
			(at -0.95 5.169 0)
			(layer "F.Fab")
			(effects
				(font
					(size 0.7 0.7)
					(thickness 0.15)
				)
				(justify left bottom)
			)
		)
		(fp_text user "Author: Antmicro"
			(at -0.95 4.169 0)
			(layer "F.Fab")
			(effects
				(font
					(size 0.7 0.7)
					(thickness 0.15)
				)
				(justify left bottom)
			)
		)
		(fp_text user "${REFERENCE}"
			(at -0.95 3.168 0)
			(layer "F.Fab")
			(effects
				(font
					(size 0.7 0.7)
					(thickness 0.15)
				)
				(justify left bottom)
			)
		)
		(pad "1" smd roundrect
			(at -0.48 0)
			(size 0.59 0.64)
			(layers "F.Cu" "F.Mask" "F.Paste")
			(roundrect_rratio 0.25)
			(net 93 "/Peripherals/FCC1_SDA2")
			(pintype "passive")
		)
		(pad "2" smd roundrect
			(at 0.48 0)
			(size 0.59 0.64)
			(layers "F.Cu" "F.Mask" "F.Paste")
			(roundrect_rratio 0.25)
			(net 365 "Net-(J4-Pad41)")
			(pintype "passive")
		)
	)
)
